(kicad_pcb
	(version 20260206)
	(generator "pcbnew")
	(generator_version "10.0")
	(general
		(thickness 1.6)
		(legacy_teardrops no)
	)
	(paper "A4")
	(title_block
		(title "03242023_DA0F0TMBIJ0_F0T_Motherboard_J_brd_V01_OCP.brd")
		(comment 1 "Grand Teton / footprints 26-32 of 6105")
	)
	(layers
		(0 "F.Cu" signal "TOP")
		(4 "In1.Cu" signal "GND")
		(6 "In2.Cu" signal "IN1")
		(8 "In3.Cu" signal "GND1")
		(10 "In4.Cu" signal "IN2")
		(12 "In5.Cu" signal "GND2")
		(14 "In6.Cu" signal "IN3")
		(16 "In7.Cu" signal "GND3")
		(18 "In8.Cu" signal "VCC")
		(20 "In9.Cu" signal "VCC1")
		(22 "In10.Cu" signal "GND4")
		(24 "In11.Cu" signal "IN4")
		(26 "In12.Cu" signal "GND5")
		(28 "In13.Cu" signal "IN5")
		(30 "In14.Cu" signal "GND6")
		(32 "In15.Cu" signal "IN6")
		(34 "In16.Cu" signal "GND7")
		(2 "B.Cu" signal "BOTTOM")
		(9 "F.Adhes" user "F.Adhesive")
		(11 "B.Adhes" user "B.Adhesive")
		(13 "F.Paste" user "Package Geometry/Pastemask Top")
		(15 "B.Paste" user "Package Geometry/Pastemask Bottom")
		(5 "F.SilkS" user "Ref Des/Silkscreen Top")
		(7 "B.SilkS" user "Ref Des/Silkscreen Bottom")
		(1 "F.Mask" user "Board Geometry/Soldermask Top")
		(3 "B.Mask" user "Board Geometry/Soldermask Bottom")
		(17 "Dwgs.User" user "User.Drawings")
		(19 "Cmts.User" user "User.Comments")
		(21 "Eco1.User" user "User.Eco1")
		(23 "Eco2.User" user "User.Eco2")
		(25 "Edge.Cuts" user "Board Geometry/Outline")
		(27 "Margin" user)
		(31 "F.CrtYd" user "Package Geometry/Place Bound Top")
		(29 "B.CrtYd" user "Package Geometry/Place Bound Bottom")
		(35 "F.Fab" user "Ref Des/Assembly Top")
		(33 "B.Fab" user "Ref Des/Assembly Bottom")
	)
	(footprint ""
		(layer "F.Cu")
		(at 119.508016 -247.715278 90)
		(property "Reference" "C427"
			(at 0 0 90)
			(layer "F.SilkS")
			(hide yes)
			(effects
				(font
					(size 1.27 1.27)
				)
			)
		)
		(property "Value" ""
			(at 0 0 90)
			(layer "F.Fab")
			(effects
				(font
					(size 1.27 1.27)
				)
			)
		)
		(duplicate_pad_numbers_are_jumpers no)
		(fp_line
			(start 0.7874 -0.4064)
			(end 0.7874 0.4064)
			(stroke
				(width 0.1524)
				(type default)
			)
			(layer "F.SilkS")
		)
		(fp_line
			(start -0.7874 -0.4064)
			(end 0.7874 -0.4064)
			(stroke
				(width 0.1524)
				(type default)
			)
			(layer "F.SilkS")
		)
		(fp_line
			(start 0.7874 0.4064)
			(end -0.7874 0.4064)
			(stroke
				(width 0.1524)
				(type default)
			)
			(layer "F.SilkS")
		)
		(fp_line
			(start -0.7874 0.4064)
			(end -0.7874 -0.4064)
			(stroke
				(width 0.1524)
				(type default)
			)
			(layer "F.SilkS")
		)
		(fp_line
			(start -0.12065 -0.305054)
			(end -0.12065 -0.2794)
			(stroke
				(width 0.1)
				(type default)
			)
			(layer "F.Fab")
		)
		(fp_line
			(start -0.67945 -0.305054)
			(end -0.12065 -0.305054)
			(stroke
				(width 0.1)
				(type default)
			)
			(layer "F.Fab")
		)
		(fp_line
			(start 0.67945 -0.3048)
			(end 0.67945 0.3048)
			(stroke
				(width 0.1)
				(type default)
			)
			(layer "F.Fab")
		)
		(fp_line
			(start 0.12065 -0.3048)
			(end 0.67945 -0.3048)
			(stroke
				(width 0.1)
				(type default)
			)
			(layer "F.Fab")
		)
		(fp_line
			(start 0.12065 -0.2794)
			(end 0.12065 -0.3048)
			(stroke
				(width 0.1)
				(type default)
			)
			(layer "F.Fab")
		)
		(fp_line
			(start -0.12065 -0.2794)
			(end 0.12065 -0.2794)
			(stroke
				(width 0.1)
				(type default)
			)
			(layer "F.Fab")
		)
		(fp_line
			(start 0.120396 0.2794)
			(end -0.12065 0.2794)
			(stroke
				(width 0.1)
				(type default)
			)
			(layer "F.Fab")
		)
		(fp_line
			(start -0.12065 0.2794)
			(end -0.12065 0.3048)
			(stroke
				(width 0.1)
				(type default)
			)
			(layer "F.Fab")
		)
		(fp_line
			(start 0.67945 0.3048)
			(end 0.120396 0.3048)
			(stroke
				(width 0.1)
				(type default)
			)
			(layer "F.Fab")
		)
		(fp_line
			(start 0.120396 0.3048)
			(end 0.120396 0.2794)
			(stroke
				(width 0.1)
				(type default)
			)
			(layer "F.Fab")
		)
		(fp_line
			(start -0.12065 0.3048)
			(end -0.67945 0.3048)
			(stroke
				(width 0.1)
				(type default)
			)
			(layer "F.Fab")
		)
		(fp_line
			(start -0.67945 0.3048)
			(end -0.67945 -0.305054)
			(stroke
				(width 0.1)
				(type default)
			)
			(layer "F.Fab")
		)
		(pad "1" smd circle
			(at -0.40005 0 90)
			(size 0 0)
			(layers "F.Cu" "F.Mask" "F.Paste")
			(net "PVCCD_HV_CPU1")
		)
		(pad "2" smd circle
			(at 0.40005 0 90)
			(size 0 0)
			(layers "F.Cu" "F.Mask" "F.Paste")
			(net "GND")
		)
	)
	(footprint ""
		(layer "F.Cu")
		(at 136.00684 -33.477708)
		(property "Reference" "U245"
			(at -1.64084 2.55143 0)
			(unlocked yes)
			(layer "F.SilkS")
			(effects
				(font
					(size 0.7874 0.5842)
					(thickness 0.1524)
				)
			)
		)
		(property "Value" ""
			(at 0 0 0)
			(layer "F.Fab")
			(effects
				(font
					(size 1.27 1.27)
				)
			)
		)
		(duplicate_pad_numbers_are_jumpers no)
		(fp_line
			(start -1.7272 1.1176)
			(end -1.7272 -1.1176)
			(stroke
				(width 0.1524)
				(type default)
			)
			(layer "F.SilkS")
		)
		(fp_line
			(start -0.254 -1.1176)
			(end -1.7272 -1.1176)
			(stroke
				(width 0.1524)
				(type default)
			)
			(layer "F.SilkS")
		)
		(fp_line
			(start 0 -0.7366)
			(end -0.254 -1.1176)
			(stroke
				(width 0.1524)
				(type default)
			)
			(layer "F.SilkS")
		)
		(fp_line
			(start 0.254 -1.1176)
			(end 0 -0.7366)
			(stroke
				(width 0.1524)
				(type default)
			)
			(layer "F.SilkS")
		)
		(fp_line
			(start 1.7272 -1.1176)
			(end 0.254 -1.1176)
			(stroke
				(width 0.1524)
				(type default)
			)
			(layer "F.SilkS")
		)
		(fp_line
			(start 1.7272 -1.1176)
			(end 1.7272 1.1176)
			(stroke
				(width 0.1524)
				(type default)
			)
			(layer "F.SilkS")
		)
		(fp_line
			(start 1.7272 1.1176)
			(end -1.7272 1.1176)
			(stroke
				(width 0.1524)
				(type default)
			)
			(layer "F.SilkS")
		)
		(fp_poly
			(pts
				(xy -2.7178 -0.268986) (xy -2.7178 -1.030986) (xy -1.9558 -0.649986)
			)
			(stroke
				(width 0)
				(type default)
			)
			(fill yes)
			(layer "F.SilkS")
		)
		(fp_line
			(start -1.5748 -1.1176)
			(end -1.5748 1.1176)
			(stroke
				(width 0.1)
				(type default)
			)
			(layer "F.Fab")
		)
		(fp_line
			(start -1.5748 1.1176)
			(end 1.5748 1.1176)
			(stroke
				(width 0.1)
				(type default)
			)
			(layer "F.Fab")
		)
		(fp_line
			(start 1.5748 -1.1176)
			(end -1.5748 -1.1176)
			(stroke
				(width 0.1)
				(type default)
			)
			(layer "F.Fab")
		)
		(fp_line
			(start 1.5748 1.1176)
			(end 1.5748 -1.1176)
			(stroke
				(width 0.1)
				(type default)
			)
			(layer "F.Fab")
		)
		(fp_poly
			(pts
				(xy -1.9558 -0.649986) (xy -2.7178 -0.268986) (xy -2.7178 -1.030986)
			)
			(stroke
				(width 0)
				(type default)
			)
			(fill yes)
			(layer "F.Fab")
		)
		(pad "1" smd rect
			(at -0.999998 -0.649986 270)
			(size 0.3556 1.1176)
			(layers "F.Cu" "F.Mask" "F.Paste")
			(net "OCP_V3_2_NOT_PRSNT_RBT_ARB_IN")
		)
		(pad "2" smd rect
			(at -0.999998 0 270)
			(size 0.3556 1.1176)
			(layers "F.Cu" "F.Mask" "F.Paste")
			(net "GND")
		)
		(pad "3" smd rect
			(at -0.999998 0.649986 270)
			(size 0.3556 1.1176)
			(layers "F.Cu" "F.Mask" "F.Paste")
			(net "OCP_V3_2_RBT_ARB_IN")
		)
		(pad "4" smd rect
			(at 0.999998 0.649986 270)
			(size 0.3556 1.1176)
			(layers "F.Cu" "F.Mask" "F.Paste")
			(net "OCP_SFF_RBT_ARB_IN_MUX2_R")
		)
		(pad "5" smd rect
			(at 0.999998 0 270)
			(size 0.3556 1.1176)
			(layers "F.Cu" "F.Mask" "F.Paste")
			(net "P3V3_AUX")
		)
		(pad "6" smd rect
			(at 0.999998 -0.649986 270)
			(size 0.3556 1.1176)
			(layers "F.Cu" "F.Mask" "F.Paste")
			(net "OCP_V3_2_PRSNT_ALL_R3_N")
		)
	)
	(footprint ""
		(layer "F.Cu")
		(at 306.71262 -56.020208 90)
		(property "Reference" "R1297"
			(at 0 0 90)
			(layer "F.SilkS")
			(hide yes)
			(effects
				(font
					(size 1.27 1.27)
				)
			)
		)
		(property "Value" ""
			(at 0 0 90)
			(layer "F.Fab")
			(effects
				(font
					(size 1.27 1.27)
				)
			)
		)
		(duplicate_pad_numbers_are_jumpers no)
		(fp_line
			(start 0.7874 -0.4064)
			(end 0.7874 0.4064)
			(stroke
				(width 0.1524)
				(type default)
			)
			(layer "F.SilkS")
		)
		(fp_line
			(start -0.7874 -0.4064)
			(end 0.7874 -0.4064)
			(stroke
				(width 0.1524)
				(type default)
			)
			(layer "F.SilkS")
		)
		(fp_line
			(start 0.7874 0.4064)
			(end -0.7874 0.4064)
			(stroke
				(width 0.1524)
				(type default)
			)
			(layer "F.SilkS")
		)
		(fp_line
			(start -0.7874 0.4064)
			(end -0.7874 -0.4064)
			(stroke
				(width 0.1524)
				(type default)
			)
			(layer "F.SilkS")
		)
		(fp_line
			(start -0.12065 -0.305054)
			(end -0.12065 -0.2794)
			(stroke
				(width 0.1)
				(type default)
			)
			(layer "F.Fab")
		)
		(fp_line
			(start -0.67945 -0.305054)
			(end -0.12065 -0.305054)
			(stroke
				(width 0.1)
				(type default)
			)
			(layer "F.Fab")
		)
		(fp_line
			(start 0.67945 -0.3048)
			(end 0.67945 0.3048)
			(stroke
				(width 0.1)
				(type default)
			)
			(layer "F.Fab")
		)
		(fp_line
			(start 0.12065 -0.3048)
			(end 0.67945 -0.3048)
			(stroke
				(width 0.1)
				(type default)
			)
			(layer "F.Fab")
		)
		(fp_line
			(start 0.12065 -0.2794)
			(end 0.12065 -0.3048)
			(stroke
				(width 0.1)
				(type default)
			)
			(layer "F.Fab")
		)
		(fp_line
			(start -0.12065 -0.2794)
			(end 0.12065 -0.2794)
			(stroke
				(width 0.1)
				(type default)
			)
			(layer "F.Fab")
		)
		(fp_line
			(start 0.120396 0.2794)
			(end -0.12065 0.2794)
			(stroke
				(width 0.1)
				(type default)
			)
			(layer "F.Fab")
		)
		(fp_line
			(start -0.12065 0.2794)
			(end -0.12065 0.3048)
			(stroke
				(width 0.1)
				(type default)
			)
			(layer "F.Fab")
		)
		(fp_line
			(start 0.67945 0.3048)
			(end 0.120396 0.3048)
			(stroke
				(width 0.1)
				(type default)
			)
			(layer "F.Fab")
		)
		(fp_line
			(start 0.120396 0.3048)
			(end 0.120396 0.2794)
			(stroke
				(width 0.1)
				(type default)
			)
			(layer "F.Fab")
		)
		(fp_line
			(start -0.12065 0.3048)
			(end -0.67945 0.3048)
			(stroke
				(width 0.1)
				(type default)
			)
			(layer "F.Fab")
		)
		(fp_line
			(start -0.67945 0.3048)
			(end -0.67945 -0.305054)
			(stroke
				(width 0.1)
				(type default)
			)
			(layer "F.Fab")
		)
		(pad "1" smd circle
			(at -0.40005 0 90)
			(size 0 0)
			(layers "F.Cu" "F.Mask" "F.Paste")
			(net "PECI_BMC_R")
		)
		(pad "2" smd circle
			(at 0.40005 0 90)
			(size 0 0)
			(layers "F.Cu" "F.Mask" "F.Paste")
			(net "PECI_BMC_B1")
		)
	)
	(footprint ""
		(layer "F.Cu")
		(at 104.347264 -260.36524 -90)
		(property "Reference" "C428"
			(at 0 0 270)
			(layer "F.SilkS")
			(hide yes)
			(effects
				(font
					(size 1.27 1.27)
				)
			)
		)
		(property "Value" ""
			(at 0 0 270)
			(layer "F.Fab")
			(effects
				(font
					(size 1.27 1.27)
				)
			)
		)
		(duplicate_pad_numbers_are_jumpers no)
		(fp_line
			(start -0.7874 0.4064)
			(end -0.7874 -0.4064)
			(stroke
				(width 0.1524)
				(type default)
			)
			(layer "F.SilkS")
		)
		(fp_line
			(start 0.7874 0.4064)
			(end -0.7874 0.4064)
			(stroke
				(width 0.1524)
				(type default)
			)
			(layer "F.SilkS")
		)
		(fp_line
			(start -0.7874 -0.4064)
			(end 0.7874 -0.4064)
			(stroke
				(width 0.1524)
				(type default)
			)
			(layer "F.SilkS")
		)
		(fp_line
			(start 0.7874 -0.4064)
			(end 0.7874 0.4064)
			(stroke
				(width 0.1524)
				(type default)
			)
			(layer "F.SilkS")
		)
		(fp_line
			(start -0.67945 0.3048)
			(end -0.67945 -0.305054)
			(stroke
				(width 0.1)
				(type default)
			)
			(layer "F.Fab")
		)
		(fp_line
			(start -0.12065 0.3048)
			(end -0.67945 0.3048)
			(stroke
				(width 0.1)
				(type default)
			)
			(layer "F.Fab")
		)
		(fp_line
			(start 0.120396 0.3048)
			(end 0.120396 0.2794)
			(stroke
				(width 0.1)
				(type default)
			)
			(layer "F.Fab")
		)
		(fp_line
			(start 0.67945 0.3048)
			(end 0.120396 0.3048)
			(stroke
				(width 0.1)
				(type default)
			)
			(layer "F.Fab")
		)
		(fp_line
			(start -0.12065 0.2794)
			(end -0.12065 0.3048)
			(stroke
				(width 0.1)
				(type default)
			)
			(layer "F.Fab")
		)
		(fp_line
			(start 0.120396 0.2794)
			(end -0.12065 0.2794)
			(stroke
				(width 0.1)
				(type default)
			)
			(layer "F.Fab")
		)
		(fp_line
			(start -0.12065 -0.2794)
			(end 0.12065 -0.2794)
			(stroke
				(width 0.1)
				(type default)
			)
			(layer "F.Fab")
		)
		(fp_line
			(start 0.12065 -0.2794)
			(end 0.12065 -0.3048)
			(stroke
				(width 0.1)
				(type default)
			)
			(layer "F.Fab")
		)
		(fp_line
			(start 0.12065 -0.3048)
			(end 0.67945 -0.3048)
			(stroke
				(width 0.1)
				(type default)
			)
			(layer "F.Fab")
		)
		(fp_line
			(start 0.67945 -0.3048)
			(end 0.67945 0.3048)
			(stroke
				(width 0.1)
				(type default)
			)
			(layer "F.Fab")
		)
		(fp_line
			(start -0.67945 -0.305054)
			(end -0.12065 -0.305054)
			(stroke
				(width 0.1)
				(type default)
			)
			(layer "F.Fab")
		)
		(fp_line
			(start -0.12065 -0.305054)
			(end -0.12065 -0.2794)
			(stroke
				(width 0.1)
				(type default)
			)
			(layer "F.Fab")
		)
		(pad "1" smd circle
			(at -0.40005 0 270)
			(size 0 0)
			(layers "F.Cu" "F.Mask" "F.Paste")
			(net "PVCCFA_EHV_FIVRA_CPU1")
		)
		(pad "2" smd circle
			(at 0.40005 0 270)
			(size 0 0)
			(layers "F.Cu" "F.Mask" "F.Paste")
			(net "GND")
		)
	)
	(footprint ""
		(layer "F.Cu")
		(at 362.646468 -357.91775)
		(property "Reference" "PC336"
			(at 0 0 0)
			(layer "F.SilkS")
			(hide yes)
			(effects
				(font
					(size 1.27 1.27)
				)
			)
		)
		(property "Value" ""
			(at 0 0 0)
			(layer "F.Fab")
			(effects
				(font
					(size 1.27 1.27)
				)
			)
		)
		(duplicate_pad_numbers_are_jumpers no)
		(fp_line
			(start -0.7874 -0.4064)
			(end 0.7874 -0.4064)
			(stroke
				(width 0.1524)
				(type default)
			)
			(layer "F.SilkS")
		)
		(fp_line
			(start -0.7874 0.4064)
			(end -0.7874 -0.4064)
			(stroke
				(width 0.1524)
				(type default)
			)
			(layer "F.SilkS")
		)
		(fp_line
			(start 0.7874 -0.4064)
			(end 0.7874 0.4064)
			(stroke
				(width 0.1524)
				(type default)
			)
			(layer "F.SilkS")
		)
		(fp_line
			(start 0.7874 0.4064)
			(end -0.7874 0.4064)
			(stroke
				(width 0.1524)
				(type default)
			)
			(layer "F.SilkS")
		)
		(fp_line
			(start -0.67945 -0.305054)
			(end -0.12065 -0.305054)
			(stroke
				(width 0.1)
				(type default)
			)
			(layer "F.Fab")
		)
		(fp_line
			(start -0.67945 0.3048)
			(end -0.67945 -0.305054)
			(stroke
				(width 0.1)
				(type default)
			)
			(layer "F.Fab")
		)
		(fp_line
			(start -0.12065 -0.305054)
			(end -0.12065 -0.2794)
			(stroke
				(width 0.1)
				(type default)
			)
			(layer "F.Fab")
		)
		(fp_line
			(start -0.12065 -0.2794)
			(end 0.12065 -0.2794)
			(stroke
				(width 0.1)
				(type default)
			)
			(layer "F.Fab")
		)
		(fp_line
			(start -0.12065 0.2794)
			(end -0.12065 0.3048)
			(stroke
				(width 0.1)
				(type default)
			)
			(layer "F.Fab")
		)
		(fp_line
			(start -0.12065 0.3048)
			(end -0.67945 0.3048)
			(stroke
				(width 0.1)
				(type default)
			)
			(layer "F.Fab")
		)
		(fp_line
			(start 0.120396 0.2794)
			(end -0.12065 0.2794)
			(stroke
				(width 0.1)
				(type default)
			)
			(layer "F.Fab")
		)
		(fp_line
			(start 0.120396 0.3048)
			(end 0.120396 0.2794)
			(stroke
				(width 0.1)
				(type default)
			)
			(layer "F.Fab")
		)
		(fp_line
			(start 0.12065 -0.3048)
			(end 0.67945 -0.3048)
			(stroke
				(width 0.1)
				(type default)
			)
			(layer "F.Fab")
		)
		(fp_line
			(start 0.12065 -0.2794)
			(end 0.12065 -0.3048)
			(stroke
				(width 0.1)
				(type default)
			)
			(layer "F.Fab")
		)
		(fp_line
			(start 0.67945 -0.3048)
			(end 0.67945 0.3048)
			(stroke
				(width 0.1)
				(type default)
			)
			(layer "F.Fab")
		)
		(fp_line
			(start 0.67945 0.3048)
			(end 0.120396 0.3048)
			(stroke
				(width 0.1)
				(type default)
			)
			(layer "F.Fab")
		)
		(pad "1" smd circle
			(at -0.40005 0)
			(size 0 0)
			(layers "F.Cu" "F.Mask" "F.Paste")
			(net "PVCCIN_CPU0_ATSEN")
		)
		(pad "2" smd circle
			(at 0.40005 0)
			(size 0 0)
			(layers "F.Cu" "F.Mask" "F.Paste")
			(net "GND")
		)
	)
	(footprint ""
		(layer "F.Cu")
		(at 10.339832 -160.50006)
		(property "Reference" "H128"
			(at -6.202172 -5.15239 0)
			(unlocked yes)
			(layer "F.SilkS")
			(effects
				(font
					(size 0.7874 0.5842)
					(thickness 0.1524)
				)
				(justify left)
			)
		)
		(property "Value" ""
			(at 0 0 0)
			(layer "F.Fab")
			(effects
				(font
					(size 1.27 1.27)
				)
			)
		)
		(duplicate_pad_numbers_are_jumpers no)
		(pad "1" thru_hole circle
			(at 0 0)
			(size 10.0076 10.0076)
			(drill 5.6134)
			(layers "*.Cu" "*.Mask")
			(remove_unused_layers no)
			(net "GND")
			(clearance -1.9431)
		)
	)
	(footprint ""
		(layer "F.Cu")
		(at 109.695742 -65.22212 -90)
		(property "Reference" "R3099"
			(at 0 0 270)
			(layer "F.SilkS")
			(hide yes)
			(effects
				(font
					(size 1.27 1.27)
				)
			)
		)
		(property "Value" ""
			(at 0 0 270)
			(layer "F.Fab")
			(effects
				(font
					(size 1.27 1.27)
				)
			)
		)
		(duplicate_pad_numbers_are_jumpers no)
		(fp_line
			(start -0.7874 0.4064)
			(end -0.7874 -0.4064)
			(stroke
				(width 0.1524)
				(type default)
			)
			(layer "F.SilkS")
		)
		(fp_line
			(start 0.7874 0.4064)
			(end -0.7874 0.4064)
			(stroke
				(width 0.1524)
				(type default)
			)
			(layer "F.SilkS")
		)
		(fp_line
			(start -0.7874 -0.4064)
			(end 0.7874 -0.4064)
			(stroke
				(width 0.1524)
				(type default)
			)
			(layer "F.SilkS")
		)
		(fp_line
			(start 0.7874 -0.4064)
			(end 0.7874 0.4064)
			(stroke
				(width 0.1524)
				(type default)
			)
			(layer "F.SilkS")
		)
		(fp_line
			(start -0.67945 0.3048)
			(end -0.67945 -0.305054)
			(stroke
				(width 0.1)
				(type default)
			)
			(layer "F.Fab")
		)
		(fp_line
			(start -0.12065 0.3048)
			(end -0.67945 0.3048)
			(stroke
				(width 0.1)
				(type default)
			)
			(layer "F.Fab")
		)
		(fp_line
			(start 0.120396 0.3048)
			(end 0.120396 0.2794)
			(stroke
				(width 0.1)
				(type default)
			)
			(layer "F.Fab")
		)
		(fp_line
			(start 0.67945 0.3048)
			(end 0.120396 0.3048)
			(stroke
				(width 0.1)
				(type default)
			)
			(layer "F.Fab")
		)
		(fp_line
			(start -0.12065 0.2794)
			(end -0.12065 0.3048)
			(stroke
				(width 0.1)
				(type default)
			)
			(layer "F.Fab")
		)
		(fp_line
			(start 0.120396 0.2794)
			(end -0.12065 0.2794)
			(stroke
				(width 0.1)
				(type default)
			)
			(layer "F.Fab")
		)
		(fp_line
			(start -0.12065 -0.2794)
			(end 0.12065 -0.2794)
			(stroke
				(width 0.1)
				(type default)
			)
			(layer "F.Fab")
		)
		(fp_line
			(start 0.12065 -0.2794)
			(end 0.12065 -0.3048)
			(stroke
				(width 0.1)
				(type default)
			)
			(layer "F.Fab")
		)
		(fp_line
			(start 0.12065 -0.3048)
			(end 0.67945 -0.3048)
			(stroke
				(width 0.1)
				(type default)
			)
			(layer "F.Fab")
		)
		(fp_line
			(start 0.67945 -0.3048)
			(end 0.67945 0.3048)
			(stroke
				(width 0.1)
				(type default)
			)
			(layer "F.Fab")
		)
		(fp_line
			(start -0.67945 -0.305054)
			(end -0.12065 -0.305054)
			(stroke
				(width 0.1)
				(type default)
			)
			(layer "F.Fab")
		)
		(fp_line
			(start -0.12065 -0.305054)
			(end -0.12065 -0.2794)
			(stroke
				(width 0.1)
				(type default)
			)
			(layer "F.Fab")
		)
		(pad "1" smd circle
			(at -0.40005 0 270)
			(size 0 0)
			(layers "F.Cu" "F.Mask" "F.Paste")
			(net "LED_PWRGD_PVCCINFAON_CPU1")
		)
		(pad "2" smd circle
			(at 0.40005 0 270)
			(size 0 0)
			(layers "F.Cu" "F.Mask" "F.Paste")
			(net "P3V3_AUX")
		)
	)
)
